# S9S_MB_2U (Grand Teton) — schematic netlist excerpt (pin names and nets, part order shuffled) for the footprints in the layout excerpt that follows; sources: Cadence DE-HDL packaged netlist, KiCad conversion of 03242023_DA0F0TMBIJ0_F0T_Motherboard_J_brd_V01_OCP.brd

R2801  Q_RES  0 5% EMPTY  pkg 0402LF  page 245 : A = SMB_FAN_3V3AUX_R_SDA ; B = SMB_FAN_3V3AUX_BUF_SDA
C1252  Q_CAP  10UF 6.3V 20% X6S  pkg C0603  page 189 : A = P1V8_PCH_PLL_AUX ; B = GND
C332  Q_CAP  47UF 4V 20% X6S  pkg C0805  page 78 : A = PVCCIN_CPU1 ; B = GND

(kicad_pcb
	(version 20260206)
	(generator "pcbnew")
	(generator_version "10.0")
	(general
		(thickness 1.6)
		(legacy_teardrops no)
	)
	(paper "A4")
	(title_block
		(title "03242023_DA0F0TMBIJ0_F0T_Motherboard_J_brd_V01_OCP.brd")
		(comment 1 "Grand Teton / footprints 5025-5027 of 6105")
	)
	(layers
		(0 "F.Cu" signal "TOP")
		(4 "In1.Cu" signal "GND")
		(6 "In2.Cu" signal "IN1")
		(8 "In3.Cu" signal "GND1")
		(10 "In4.Cu" signal "IN2")
		(12 "In5.Cu" signal "GND2")
		(14 "In6.Cu" signal "IN3")
		(16 "In7.Cu" signal "GND3")
		(18 "In8.Cu" signal "VCC")
		(20 "In9.Cu" signal "VCC1")
		(22 "In10.Cu" signal "GND4")
		(24 "In11.Cu" signal "IN4")
		(26 "In12.Cu" signal "GND5")
		(28 "In13.Cu" signal "IN5")
		(30 "In14.Cu" signal "GND6")
		(32 "In15.Cu" signal "IN6")
		(34 "In16.Cu" signal "GND7")
		(2 "B.Cu" signal "BOTTOM")
		(9 "F.Adhes" user "F.Adhesive")
		(11 "B.Adhes" user "B.Adhesive")
		(13 "F.Paste" user "Package Geometry/Pastemask Top")
		(15 "B.Paste" user "Package Geometry/Pastemask Bottom")
		(5 "F.SilkS" user "Ref Des/Silkscreen Top")
		(7 "B.SilkS" user "Ref Des/Silkscreen Bottom")
		(1 "F.Mask" user "Board Geometry/Soldermask Top")
		(3 "B.Mask" user "Board Geometry/Soldermask Bottom")
		(17 "Dwgs.User" user "User.Drawings")
		(19 "Cmts.User" user "User.Comments")
		(21 "Eco1.User" user "User.Eco1")
		(23 "Eco2.User" user "User.Eco2")
		(25 "Edge.Cuts" user "Board Geometry/Outline")
		(27 "Margin" user)
		(31 "F.CrtYd" user "Package Geometry/Place Bound Top")
		(29 "B.CrtYd" user "Package Geometry/Place Bound Bottom")
		(35 "F.Fab" user "Ref Des/Assembly Top")
		(33 "B.Fab" user "Ref Des/Assembly Bottom")
	)
	(footprint ""
		(layer "B.Cu")
		(at 179.506626 -417.030154 180)
		(property "Reference" "R2801"
			(at 0 0 0)
			(layer "B.SilkS")
			(hide yes)
			(effects
				(font
					(size 1.27 1.27)
				)
				(justify mirror)
			)
		)
		(property "Value" ""
			(at 0 0 0)
			(layer "B.Fab")
			(effects
				(font
					(size 1.27 1.27)
				)
				(justify mirror)
			)
		)
		(duplicate_pad_numbers_are_jumpers no)
		(fp_line
			(start 0.7874 0.4064)
			(end 0.7874 -0.4064)
			(stroke
				(width 0.1524)
				(type default)
			)
			(layer "B.SilkS")
		)
		(fp_line
			(start 0.7874 -0.4064)
			(end -0.7874 -0.4064)
			(stroke
				(width 0.1524)
				(type default)
			)
			(layer "B.SilkS")
		)
		(fp_line
			(start -0.7874 0.4064)
			(end 0.7874 0.4064)
			(stroke
				(width 0.1524)
				(type default)
			)
			(layer "B.SilkS")
		)
		(fp_line
			(start -0.7874 -0.4064)
			(end -0.7874 0.4064)
			(stroke
				(width 0.1524)
				(type default)
			)
			(layer "B.SilkS")
		)
		(fp_line
			(start 0.67945 0.3048)
			(end 0.67945 -0.305054)
			(stroke
				(width 0.1)
				(type default)
			)
			(layer "B.Fab")
		)
		(fp_line
			(start 0.67945 -0.305054)
			(end 0.12065 -0.305054)
			(stroke
				(width 0.1)
				(type default)
			)
			(layer "B.Fab")
		)
		(fp_line
			(start 0.12065 0.3048)
			(end 0.67945 0.3048)
			(stroke
				(width 0.1)
				(type default)
			)
			(layer "B.Fab")
		)
		(fp_line
			(start 0.12065 0.2794)
			(end 0.12065 0.3048)
			(stroke
				(width 0.1)
				(type default)
			)
			(layer "B.Fab")
		)
		(fp_line
			(start 0.12065 -0.2794)
			(end -0.12065 -0.2794)
			(stroke
				(width 0.1)
				(type default)
			)
			(layer "B.Fab")
		)
		(fp_line
			(start 0.12065 -0.305054)
			(end 0.12065 -0.2794)
			(stroke
				(width 0.1)
				(type default)
			)
			(layer "B.Fab")
		)
		(fp_line
			(start -0.120396 0.3048)
			(end -0.120396 0.2794)
			(stroke
				(width 0.1)
				(type default)
			)
			(layer "B.Fab")
		)
		(fp_line
			(start -0.120396 0.2794)
			(end 0.12065 0.2794)
			(stroke
				(width 0.1)
				(type default)
			)
			(layer "B.Fab")
		)
		(fp_line
			(start -0.12065 -0.2794)
			(end -0.12065 -0.3048)
			(stroke
				(width 0.1)
				(type default)
			)
			(layer "B.Fab")
		)
		(fp_line
			(start -0.12065 -0.3048)
			(end -0.67945 -0.3048)
			(stroke
				(width 0.1)
				(type default)
			)
			(layer "B.Fab")
		)
		(fp_line
			(start -0.67945 0.3048)
			(end -0.120396 0.3048)
			(stroke
				(width 0.1)
				(type default)
			)
			(layer "B.Fab")
		)
		(fp_line
			(start -0.67945 -0.3048)
			(end -0.67945 0.3048)
			(stroke
				(width 0.1)
				(type default)
			)
			(layer "B.Fab")
		)
		(pad "1" smd circle
			(at 0.40005 0)
			(size 0 0)
			(layers "B.Cu" "B.Mask" "B.Paste")
			(net "SMB_FAN_3V3AUX_R_SDA")
		)
		(pad "2" smd circle
			(at -0.40005 0)
			(size 0 0)
			(layers "B.Cu" "B.Mask" "B.Paste")
			(net "SMB_FAN_3V3AUX_BUF_SDA")
		)
	)
	(footprint ""
		(layer "B.Cu")
		(at 346.026486 -54.487826 90)
		(property "Reference" "C1252"
			(at 0 0 90)
			(layer "B.SilkS")
			(hide yes)
			(effects
				(font
					(size 1.27 1.27)
				)
				(justify mirror)
			)
		)
		(property "Value" ""
			(at 0 0 90)
			(layer "B.Fab")
			(effects
				(font
					(size 1.27 1.27)
				)
				(justify mirror)
			)
		)
		(duplicate_pad_numbers_are_jumpers no)
		(fp_line
			(start 1.125982 -0.5842)
			(end -1.2954 -0.5842)
			(stroke
				(width 0.1524)
				(type default)
			)
			(layer "B.SilkS")
		)
		(fp_line
			(start 0 -0.5842)
			(end 0 0.5842)
			(stroke
				(width 0.1524)
				(type default)
			)
			(layer "B.SilkS")
		)
		(fp_line
			(start -1.2954 -0.5842)
			(end -1.2954 0.5842)
			(stroke
				(width 0.1524)
				(type default)
			)
			(layer "B.SilkS")
		)
		(fp_line
			(start 1.2954 0.5842)
			(end 1.2954 -0.350266)
			(stroke
				(width 0.1524)
				(type default)
			)
			(layer "B.SilkS")
		)
		(fp_line
			(start -1.2954 0.5842)
			(end 1.2954 0.5842)
			(stroke
				(width 0.1524)
				(type default)
			)
			(layer "B.SilkS")
		)
		(fp_line
			(start 0.8636 -0.4572)
			(end -0.8636 -0.4572)
			(stroke
				(width 0.1)
				(type default)
			)
			(layer "B.Fab")
		)
		(fp_line
			(start -0.8636 -0.4572)
			(end -0.8636 -0.4064)
			(stroke
				(width 0.1)
				(type default)
			)
			(layer "B.Fab")
		)
		(fp_line
			(start 1.1938 -0.4064)
			(end 0.8636 -0.4064)
			(stroke
				(width 0.1)
				(type default)
			)
			(layer "B.Fab")
		)
		(fp_line
			(start 0.8636 -0.4064)
			(end 0.8636 -0.4572)
			(stroke
				(width 0.1)
				(type default)
			)
			(layer "B.Fab")
		)
		(fp_line
			(start -0.8636 -0.4064)
			(end -1.1938 -0.4064)
			(stroke
				(width 0.1)
				(type default)
			)
			(layer "B.Fab")
		)
		(fp_line
			(start -1.1938 -0.4064)
			(end -1.1938 0.4064)
			(stroke
				(width 0.1)
				(type default)
			)
			(layer "B.Fab")
		)
		(fp_line
			(start 1.1938 0.4064)
			(end 1.1938 -0.4064)
			(stroke
				(width 0.1)
				(type default)
			)
			(layer "B.Fab")
		)
		(fp_line
			(start 0.8636 0.4064)
			(end 1.1938 0.4064)
			(stroke
				(width 0.1)
				(type default)
			)
			(layer "B.Fab")
		)
		(fp_line
			(start -0.8636 0.4064)
			(end -0.8636 0.4572)
			(stroke
				(width 0.1)
				(type default)
			)
			(layer "B.Fab")
		)
		(fp_line
			(start -1.1938 0.4064)
			(end -0.8636 0.4064)
			(stroke
				(width 0.1)
				(type default)
			)
			(layer "B.Fab")
		)
		(fp_line
			(start 0.8636 0.4572)
			(end 0.8636 0.4064)
			(stroke
				(width 0.1)
				(type default)
			)
			(layer "B.Fab")
		)
		(fp_line
			(start -0.8636 0.4572)
			(end 0.8636 0.4572)
			(stroke
				(width 0.1)
				(type default)
			)
			(layer "B.Fab")
		)
		(pad "1" smd rect
			(at 0.7366 0)
			(size 0.7112 0.8128)
			(layers "B.Cu" "B.Mask" "B.Paste")
			(net "P1V8_PCH_PLL_AUX")
		)
		(pad "2" smd rect
			(at -0.7366 0)
			(size 0.7112 0.8128)
			(layers "B.Cu" "B.Mask" "B.Paste")
			(net "GND")
		)
	)
	(footprint ""
		(layer "B.Cu")
		(at 118.18112 -255.8542 -90)
		(property "Reference" "C332"
			(at 0 0 90)
			(layer "B.SilkS")
			(hide yes)
			(effects
				(font
					(size 1.27 1.27)
				)
				(justify mirror)
			)
		)
		(property "Value" ""
			(at 0 0 90)
			(layer "B.Fab")
			(effects
				(font
					(size 1.27 1.27)
				)
				(justify mirror)
			)
		)
		(duplicate_pad_numbers_are_jumpers no)
		(fp_line
			(start -1.524 0.762)
			(end 1.524 0.762)
			(stroke
				(width 0.1524)
				(type default)
			)
			(layer "B.SilkS")
		)
		(fp_line
			(start 1.524 0.762)
			(end 1.524 -0.762)
			(stroke
				(width 0.1524)
				(type default)
			)
			(layer "B.SilkS")
		)
		(fp_line
			(start -1.524 -0.762)
			(end -1.524 0.762)
			(stroke
				(width 0.1524)
				(type default)
			)
			(layer "B.SilkS")
		)
		(fp_line
			(start 1.524 -0.762)
			(end -1.524 -0.762)
			(stroke
				(width 0.1524)
				(type default)
			)
			(layer "B.SilkS")
		)
		(fp_line
			(start -1.1049 0.724916)
			(end -1.1049 -0.724916)
			(stroke
				(width 0.1)
				(type default)
			)
			(layer "B.Fab")
		)
		(fp_line
			(start 1.1049 0.724916)
			(end -1.1049 0.724916)
			(stroke
				(width 0.1)
				(type default)
			)
			(layer "B.Fab")
		)
		(fp_line
			(start -1.1049 -0.724916)
			(end 1.1049 -0.724916)
			(stroke
				(width 0.1)
				(type default)
			)
			(layer "B.Fab")
		)
		(fp_line
			(start 1.1049 -0.724916)
			(end 1.1049 0.724916)
			(stroke
				(width 0.1)
				(type default)
			)
			(layer "B.Fab")
		)
		(pad "1" smd rect
			(at 0.889 0 270)
			(size 1.016 1.27)
			(layers "B.Cu" "B.Mask" "B.Paste")
			(net "PVCCIN_CPU1")
		)
		(pad "2" smd rect
			(at -0.889 0 270)
			(size 1.016 1.27)
			(layers "B.Cu" "B.Mask" "B.Paste")
			(net "GND")
		)
	)
)
